# TIMECARD (Time Appliance Project (Time Card)) — schematic netlist excerpt (pin names and nets, part order shuffled) for the footprints in the layout excerpt that follows; sources: Cadence DE-HDL packaged netlist, KiCad conversion of R4006-B0001-02_R01.brd

C167  CAPACITOR  4.7UF 6.3V 20%  pkg SMC_0402R_H026  page 14 : \1\ = XP3R3V_FPGA ; \2\ = SG
R336  RESISTOR  1KOHM 1%  pkg SMC_0402R_H016  page 17 : \1\ = UNNAMED_6_LM75BDPTSSOP8_I34_A1 ; \2\ = SG

(kicad_pcb
	(version 20260206)
	(generator "pcbnew")
	(generator_version "10.0")
	(general
		(thickness 1.6)
		(legacy_teardrops no)
	)
	(paper "A4")
	(title_block
		(title "timecard-production-celestica-r4006 — R4006-B0001-02_R01.brd")
		(comment 1 "Time Appliance Project (Time Card) / footprints 867-868 of 1113")
	)
	(layers
		(0 "F.Cu" signal "TOP")
		(4 "In1.Cu" signal "L02_GND1")
		(6 "In2.Cu" signal "L03_SIG1")
		(8 "In3.Cu" signal "L04_GND2")
		(10 "In4.Cu" signal "L05_VCC1")
		(12 "In5.Cu" signal "L06_VCC2")
		(14 "In6.Cu" signal "L07_GND3")
		(16 "In7.Cu" signal "L08_SIG2")
		(18 "In8.Cu" signal "L09_GND4")
		(2 "B.Cu" signal "BOTTOM")
		(9 "F.Adhes" user "F.Adhesive")
		(11 "B.Adhes" user "B.Adhesive")
		(13 "F.Paste" user "Package Geometry/Pastemask Top")
		(15 "B.Paste" user "Package Geometry/Pastemask Bottom")
		(5 "F.SilkS" user "Ref Des/Silkscreen Top")
		(7 "B.SilkS" user "Ref Des/Silkscreen Bottom")
		(1 "F.Mask" user "Board Geometry/Soldermask Top")
		(3 "B.Mask" user "Board Geometry/Soldermask Bottom")
		(17 "Dwgs.User" user "User.Drawings")
		(19 "Cmts.User" user "User.Comments")
		(21 "Eco1.User" user "User.Eco1")
		(23 "Eco2.User" user "User.Eco2")
		(25 "Edge.Cuts" user "Board Geometry/Outline")
		(27 "Margin" user)
		(31 "F.CrtYd" user "Package Geometry/Place Bound Top")
		(29 "B.CrtYd" user "Package Geometry/Place Bound Bottom")
		(35 "F.Fab" user "Ref Des/Assembly Top")
		(33 "B.Fab" user "Ref Des/Assembly Bottom")
	)
	(footprint ""
		(layer "B.Cu")
		(at 101.347016 -48.823118)
		(property "Reference" "C167"
			(at -1.144016 1.052068 0)
			(unlocked yes)
			(layer "B.SilkS")
			(effects
				(font
					(size 0.635 0.4064)
					(thickness 0.1524)
				)
				(justify mirror)
			)
		)
		(property "Value" "VAL*"
			(at 0 3.718306 0)
			(unlocked yes)
			(layer "B.Fab")
			(hide yes)
			(effects
				(font
					(size 0.7874 0.5842)
					(thickness 0.127)
				)
				(justify mirror)
			)
		)
		(property "Device Type" "CAPACITOR-G105-0F475-BM,4.7UF,A"
			(at 0 1.432306 0)
			(unlocked yes)
			(layer "B.Fab")
			(hide yes)
			(effects
				(font
					(size 0.7874 0.5842)
					(thickness 0.127)
				)
				(justify mirror)
			)
		)
		(property "User Part Number" "PARTNUM*"
			(at 0 2.575306 0)
			(unlocked yes)
			(layer "Cmts.User")
			(hide yes)
			(effects
				(font
					(size 0.7874 0.5842)
					(thickness 0.127)
				)
				(justify mirror)
			)
		)
		(property "Tolerance" "TOL*"
			(at 0 4.861306 0)
			(unlocked yes)
			(layer "Cmts.User")
			(hide yes)
			(effects
				(font
					(size 0.7874 0.5842)
					(thickness 0.127)
				)
				(justify mirror)
			)
		)
		(duplicate_pad_numbers_are_jumpers no)
		(fp_line
			(start -0.970026 -0.4699)
			(end -0.970026 0.4699)
			(stroke
				(width 0.1)
				(type default)
			)
			(layer "B.SilkS")
		)
		(fp_line
			(start -0.970026 0.4699)
			(end 0.970026 0.4699)
			(stroke
				(width 0.1)
				(type default)
			)
			(layer "B.SilkS")
		)
		(fp_line
			(start 0.970026 -0.4699)
			(end -0.970026 -0.4699)
			(stroke
				(width 0.1)
				(type default)
			)
			(layer "B.SilkS")
		)
		(fp_line
			(start 0.970026 0.4699)
			(end 0.970026 -0.4699)
			(stroke
				(width 0.1)
				(type default)
			)
			(layer "B.SilkS")
		)
		(fp_poly
			(pts
				(xy 0.970026 0.4699) (xy -0.970026 0.4699) (xy -0.970026 -0.4699) (xy 0.970026 -0.4699)
			)
			(stroke
				(width 0)
				(type default)
			)
			(fill no)
			(layer "B.CrtYd")
		)
		(fp_line
			(start -0.508 -0.3048)
			(end -0.508 0.3048)
			(stroke
				(width 0.1)
				(type default)
			)
			(layer "B.Fab")
		)
		(fp_line
			(start -0.508 0.3048)
			(end 0.508 0.3048)
			(stroke
				(width 0.1)
				(type default)
			)
			(layer "B.Fab")
		)
		(fp_line
			(start 0.508 -0.3048)
			(end -0.508 -0.3048)
			(stroke
				(width 0.1)
				(type default)
			)
			(layer "B.Fab")
		)
		(fp_line
			(start 0.508 0.3048)
			(end 0.508 -0.3048)
			(stroke
				(width 0.1)
				(type default)
			)
			(layer "B.Fab")
		)
		(pad "1" smd circle
			(at 0.500126 0 180)
			(size 0.635 0.635)
			(layers "B.Cu" "B.Mask" "B.Paste")
			(net "XP3R3V_FPGA")
		)
		(pad "2" smd circle
			(at -0.500126 0 180)
			(size 0.635 0.635)
			(layers "B.Cu" "B.Mask" "B.Paste")
			(net "SG")
		)
	)
	(footprint ""
		(layer "B.Cu")
		(at 5.588 -73.025)
		(property "Reference" "R336"
			(at -2.921 -0.59563 0)
			(unlocked yes)
			(layer "B.SilkS")
			(effects
				(font
					(size 0.7874 0.5842)
					(thickness 0.1524)
				)
				(justify mirror)
			)
		)
		(property "Value" "VAL*"
			(at -0.02032 2.13233 0)
			(unlocked yes)
			(layer "B.Fab")
			(hide yes)
			(effects
				(font
					(size 0.7874 0.5842)
					(thickness 0.1524)
				)
				(justify mirror)
			)
		)
		(property "Tolerance" "TOL*"
			(at -0.044704 3.05435 0)
			(unlocked yes)
			(layer "Cmts.User")
			(hide yes)
			(effects
				(font
					(size 0.7874 0.5842)
					(thickness 0.1524)
				)
				(justify mirror)
			)
		)
		(property "User Part Number" "PARTNUM*"
			(at -0.02032 4.024884 0)
			(unlocked yes)
			(layer "Cmts.User")
			(hide yes)
			(effects
				(font
					(size 0.7874 0.5842)
					(thickness 0.1524)
				)
				(justify mirror)
			)
		)
		(property "Device Type" "RESISTOR-G155-11001-01,1KOHM,1%"
			(at -0.008382 1.210564 0)
			(unlocked yes)
			(layer "B.Fab")
			(hide yes)
			(effects
				(font
					(size 0.7874 0.5842)
					(thickness 0.1524)
				)
				(justify mirror)
			)
		)
		(duplicate_pad_numbers_are_jumpers no)
		(fp_line
			(start -1.143 -0.5588)
			(end 1.143 -0.5588)
			(stroke
				(width 0.1)
				(type default)
			)
			(layer "B.SilkS")
		)
		(fp_line
			(start -1.143 0.5588)
			(end -1.143 -0.5588)
			(stroke
				(width 0.1)
				(type default)
			)
			(layer "B.SilkS")
		)
		(fp_line
			(start 1.143 -0.5588)
			(end 1.143 0.5588)
			(stroke
				(width 0.1)
				(type default)
			)
			(layer "B.SilkS")
		)
		(fp_line
			(start 1.143 0.5588)
			(end -1.143 0.5588)
			(stroke
				(width 0.1)
				(type default)
			)
			(layer "B.SilkS")
		)
		(fp_rect
			(start 1.143 0.5588)
			(end -1.143 -0.5588)
			(stroke
				(width 0)
				(type default)
			)
			(fill no)
			(layer "B.CrtYd")
		)
		(fp_line
			(start -0.508 -0.3048)
			(end 0.508 -0.3048)
			(stroke
				(width 0.1)
				(type default)
			)
			(layer "B.Fab")
		)
		(fp_line
			(start -0.508 0.3048)
			(end -0.508 -0.3048)
			(stroke
				(width 0.1)
				(type default)
			)
			(layer "B.Fab")
		)
		(fp_line
			(start 0.508 -0.3048)
			(end 0.508 0.3048)
			(stroke
				(width 0.1)
				(type default)
			)
			(layer "B.Fab")
		)
		(fp_line
			(start 0.508 0.3048)
			(end -0.508 0.3048)
			(stroke
				(width 0.1)
				(type default)
			)
			(layer "B.Fab")
		)
		(pad "1" smd rect
			(at 0.5334 0 180)
			(size 0.7112 0.6096)
			(layers "B.Cu" "B.Mask" "B.Paste")
			(net "UNNAMED_6_LM75BDPTSSOP8_I34_A1")
		)
		(pad "2" smd rect
			(at -0.5334 0 180)
			(size 0.7112 0.6096)
			(layers "B.Cu" "B.Mask" "B.Paste")
			(net "SG")
		)
		(zone
			(layer "B.Cu")
			(hatch none 0.5)
			(connect_pads
				(clearance 0)
			)
			(min_thickness 0.25)
			(keepout
				(tracks allowed)
				(vias not_allowed)
				(pads allowed)
				(copperpour not_allowed)
				(footprints allowed)
			)
			(placement
				(enabled no)
				(sheetname "")
			)
			(fill
				(thermal_gap 0.5)
				(thermal_bridge_width 0.5)
				(island_removal_mode 0)
			)
			(polygon
				(pts
					(xy 5.6642 -72.7202) (xy 5.6642 -73.3298) (xy 5.5118 -73.3298) (xy 5.5118 -72.7202)
				)
			)
		)
	)
)
